(kicad_pcb
	(version 20260206)
	(generator "pcbnew")
	(generator_version "10.0")
	(general
		(thickness 1.6)
		(legacy_teardrops no)
	)
	(paper "A4")
	(title_block
		(title "dpb — 14545-sa.0730WZS0815.brd")
		(comment 1 "Honey Badger (Wiwynn) / footprints 222-228 of 1066")
	)
	(layers
		(0 "F.Cu" signal "TOP")
		(4 "In1.Cu" signal "L2GND")
		(6 "In2.Cu" signal "L3")
		(8 "In3.Cu" signal "L4VCC")
		(10 "In4.Cu" signal "L5VCC")
		(12 "In5.Cu" signal "L6")
		(14 "In6.Cu" signal "L7GND")
		(2 "B.Cu" signal "BOTTOM")
		(9 "F.Adhes" user "F.Adhesive")
		(11 "B.Adhes" user "B.Adhesive")
		(13 "F.Paste" user "Package Geometry/Pastemask Top")
		(15 "B.Paste" user "Package Geometry/Pastemask Bottom")
		(5 "F.SilkS" user "Ref Des/Silkscreen Top")
		(7 "B.SilkS" user "Ref Des/Silkscreen Bottom")
		(1 "F.Mask" user "Board Geometry/Soldermask Top")
		(3 "B.Mask" user "Board Geometry/Soldermask Bottom")
		(17 "Dwgs.User" user "User.Drawings")
		(19 "Cmts.User" user "User.Comments")
		(21 "Eco1.User" user "User.Eco1")
		(23 "Eco2.User" user "User.Eco2")
		(25 "Edge.Cuts" user "Board Geometry/Outline")
		(27 "Margin" user)
		(31 "F.CrtYd" user "Package Geometry/Place Bound Top")
		(29 "B.CrtYd" user "Package Geometry/Place Bound Bottom")
		(35 "F.Fab" user "Ref Des/Assembly Top")
		(33 "B.Fab" user "Ref Des/Assembly Bottom")
	)
	(footprint ""
		(layer "F.Cu")
		(at 163.588446 -458.631036 180)
		(property "Reference" "R390"
			(at 0 0 180)
			(layer "F.SilkS")
			(hide yes)
			(effects
				(font
					(size 1.27 1.27)
				)
			)
		)
		(property "Value" "10KR2F-2-GP"
			(at 0.064008 -3.993896 180)
			(unlocked yes)
			(layer "F.Fab")
			(hide yes)
			(effects
				(font
					(size 1.016 1.016)
					(thickness 0.1524)
				)
			)
		)
		(property "Device Type" "R402H16"
			(at 0.064008 -5.517896 180)
			(unlocked yes)
			(layer "F.Fab")
			(hide yes)
			(effects
				(font
					(size 1.016 1.016)
					(thickness 0.1524)
				)
			)
		)
		(duplicate_pad_numbers_are_jumpers no)
		(fp_line
			(start 0.508 -0.9398)
			(end -0.508 -0.9398)
			(stroke
				(width 0.1524)
				(type default)
			)
			(layer "F.SilkS")
		)
		(fp_line
			(start -0.508 -0.9398)
			(end -0.508 0.9398)
			(stroke
				(width 0.1524)
				(type default)
			)
			(layer "F.SilkS")
		)
		(fp_rect
			(start -0.508 0.9398)
			(end 0.508 -0.9398)
			(stroke
				(width 0)
				(type default)
			)
			(fill no)
			(layer "F.CrtYd")
		)
		(fp_rect
			(start -0.508 0.9398)
			(end 0.508 -0.9398)
			(stroke
				(width 0)
				(type default)
			)
			(fill no)
			(layer "F.Fab")
		)
		(pad "1" smd custom
			(at 0 -0.4445 180)
			(size 0.1397 0.1397)
			(layers "F.Cu" "F.Mask" "F.Paste")
			(net "P5VA_DIV")
			(options
				(clearance outline)
				(anchor circle)
			)
			(primitives
				(gr_poly
					(pts
						(arc
							(start -0.1778 -0.2794)
							(mid -0.249642 -0.249642)
							(end -0.2794 -0.1778)
						)
						(arc
							(start -0.2794 0.1778)
							(mid -0.249642 0.249642)
							(end -0.1778 0.2794)
						)
						(arc
							(start 0.1778 0.2794)
							(mid 0.249642 0.249642)
							(end 0.2794 0.1778)
						)
						(arc
							(start 0.2794 -0.1778)
							(mid 0.249642 -0.249642)
							(end 0.1778 -0.2794)
						)
					)
					(width 0)
					(fill yes)
				)
			)
		)
		(pad "2" smd custom
			(at 0 0.4445 180)
			(size 0.1397 0.1397)
			(layers "F.Cu" "F.Mask" "F.Paste")
			(net "GND")
			(options
				(clearance outline)
				(anchor circle)
			)
			(primitives
				(gr_poly
					(pts
						(arc
							(start -0.1778 -0.2794)
							(mid -0.249642 -0.249642)
							(end -0.2794 -0.1778)
						)
						(arc
							(start -0.2794 0.1778)
							(mid -0.249642 0.249642)
							(end -0.1778 0.2794)
						)
						(arc
							(start 0.1778 0.2794)
							(mid 0.249642 0.249642)
							(end 0.2794 0.1778)
						)
						(arc
							(start 0.2794 -0.1778)
							(mid 0.249642 -0.249642)
							(end 0.1778 -0.2794)
						)
					)
					(width 0)
					(fill yes)
				)
			)
		)
	)
	(footprint ""
		(layer "F.Cu")
		(at 10.8458 -104.2924)
		(property "Reference" "R407"
			(at 0 0 0)
			(layer "F.SilkS")
			(hide yes)
			(effects
				(font
					(size 1.27 1.27)
				)
			)
		)
		(property "Value" "100R2J-2-GP"
			(at 0.064008 -3.993896 0)
			(unlocked yes)
			(layer "F.Fab")
			(hide yes)
			(effects
				(font
					(size 1.016 1.016)
					(thickness 0.1524)
				)
			)
		)
		(property "Device Type" "R402H14"
			(at 0.064008 -5.517896 0)
			(unlocked yes)
			(layer "F.Fab")
			(hide yes)
			(effects
				(font
					(size 1.016 1.016)
					(thickness 0.1524)
				)
			)
		)
		(duplicate_pad_numbers_are_jumpers no)
		(fp_line
			(start -0.508 -0.9398)
			(end -0.508 0.9398)
			(stroke
				(width 0.1524)
				(type default)
			)
			(layer "F.SilkS")
		)
		(fp_line
			(start 0.508 -0.9398)
			(end -0.508 -0.9398)
			(stroke
				(width 0.1524)
				(type default)
			)
			(layer "F.SilkS")
		)
		(fp_rect
			(start -0.508 0.9398)
			(end 0.508 -0.9398)
			(stroke
				(width 0)
				(type default)
			)
			(fill no)
			(layer "F.CrtYd")
		)
		(fp_rect
			(start -0.508 0.9398)
			(end 0.508 -0.9398)
			(stroke
				(width 0)
				(type default)
			)
			(fill no)
			(layer "F.Fab")
		)
		(pad "1" smd custom
			(at 0 -0.4445)
			(size 0.1397 0.1397)
			(layers "F.Cu" "F.Mask" "F.Paste")
			(net "DPB_HW_REV")
			(options
				(clearance outline)
				(anchor circle)
			)
			(primitives
				(gr_poly
					(pts
						(arc
							(start -0.1778 -0.2794)
							(mid -0.249642 -0.249642)
							(end -0.2794 -0.1778)
						)
						(arc
							(start -0.2794 0.1778)
							(mid -0.249642 0.249642)
							(end -0.1778 0.2794)
						)
						(arc
							(start 0.1778 0.2794)
							(mid 0.249642 0.249642)
							(end 0.2794 0.1778)
						)
						(arc
							(start 0.2794 -0.1778)
							(mid 0.249642 -0.249642)
							(end 0.1778 -0.2794)
						)
					)
					(width 0)
					(fill yes)
				)
			)
		)
		(pad "2" smd custom
			(at 0 0.4445)
			(size 0.1397 0.1397)
			(layers "F.Cu" "F.Mask" "F.Paste")
			(net "GND")
			(options
				(clearance outline)
				(anchor circle)
			)
			(primitives
				(gr_poly
					(pts
						(arc
							(start -0.1778 -0.2794)
							(mid -0.249642 -0.249642)
							(end -0.2794 -0.1778)
						)
						(arc
							(start -0.2794 0.1778)
							(mid -0.249642 0.249642)
							(end -0.1778 0.2794)
						)
						(arc
							(start 0.1778 0.2794)
							(mid 0.249642 0.249642)
							(end 0.2794 0.1778)
						)
						(arc
							(start 0.2794 -0.1778)
							(mid 0.249642 -0.249642)
							(end 0.1778 -0.2794)
						)
					)
					(width 0)
					(fill yes)
				)
			)
		)
	)
	(footprint ""
		(layer "F.Cu")
		(at 46.659546 -419.208458 -90)
		(property "Reference" "Q22"
			(at 0 0 270)
			(layer "F.SilkS")
			(hide yes)
			(effects
				(font
					(size 1.27 1.27)
				)
			)
		)
		(property "Value" "2N7002DW-7F-GP"
			(at -2.3622 -8.2042 270)
			(unlocked yes)
			(layer "F.Fab")
			(hide yes)
			(effects
				(font
					(size 1.016 1.016)
					(thickness 0.1524)
				)
			)
		)
		(property "Device Type" "SOT-363H44"
			(at -2.3622 -10.1092 270)
			(unlocked yes)
			(layer "F.Fab")
			(hide yes)
			(effects
				(font
					(size 1.016 1.016)
					(thickness 0.1524)
				)
			)
		)
		(duplicate_pad_numbers_are_jumpers no)
		(fp_line
			(start -1.4478 1.7018)
			(end 1.4478 1.7018)
			(stroke
				(width 0.1524)
				(type default)
			)
			(layer "F.SilkS")
		)
		(fp_line
			(start 1.4478 1.7018)
			(end 1.4478 -1.7018)
			(stroke
				(width 0.1524)
				(type default)
			)
			(layer "F.SilkS")
		)
		(fp_line
			(start -1.27 1.524)
			(end -1.27 0.6604)
			(stroke
				(width 0.4826)
				(type default)
			)
			(layer "F.SilkS")
		)
		(fp_line
			(start -1.4478 -1.7018)
			(end -1.4478 1.7018)
			(stroke
				(width 0.1524)
				(type default)
			)
			(layer "F.SilkS")
		)
		(fp_line
			(start 1.4478 -1.7018)
			(end -1.4478 -1.7018)
			(stroke
				(width 0.1524)
				(type default)
			)
			(layer "F.SilkS")
		)
		(fp_poly
			(pts
				(xy -1.524 -1.778) (xy 1.524 -1.778) (xy 1.524 1.778) (xy -1.524 1.778)
			)
			(stroke
				(width 0)
				(type default)
			)
			(fill no)
			(layer "F.CrtYd")
		)
		(fp_poly
			(pts
				(xy -1.524 -1.778) (xy 1.524 -1.778) (xy 1.524 1.778) (xy -1.524 1.778)
			)
			(stroke
				(width 0)
				(type default)
			)
			(fill no)
			(layer "F.Fab")
		)
		(pad "1" smd rect
			(at -0.65024 0.9398 270)
			(size 0.4064 1.016)
			(layers "F.Cu" "F.Mask" "F.Paste")
			(net "GND")
		)
		(pad "2" smd rect
			(at 0 0.9398 270)
			(size 0.4064 1.016)
			(layers "F.Cu" "F.Mask" "F.Paste")
			(net "SW_PWR_R_HDD10")
		)
		(pad "3" smd rect
			(at 0.65024 0.9398 270)
			(size 0.4064 1.016)
			(layers "F.Cu" "F.Mask" "F.Paste")
			(net "SW_HDD10_P")
		)
		(pad "4" smd rect
			(at 0.65024 -0.9398 270)
			(size 0.4064 1.016)
			(layers "F.Cu" "F.Mask" "F.Paste")
			(net "GND")
		)
		(pad "5" smd rect
			(at 0 -0.9398 270)
			(size 0.4064 1.016)
			(layers "F.Cu" "F.Mask" "F.Paste")
			(net "SW_HDD10_G")
		)
		(pad "6" smd rect
			(at -0.65024 -0.9398 270)
			(size 0.4064 1.016)
			(layers "F.Cu" "F.Mask" "F.Paste")
			(net "SW_HDD10_R")
		)
	)
	(footprint ""
		(layer "F.Cu")
		(at 217.799412 -58.019696 -90)
		(property "Reference" "C167"
			(at 0 0 270)
			(layer "F.SilkS")
			(hide yes)
			(effects
				(font
					(size 1.27 1.27)
				)
			)
		)
		(property "Value" "SCD01U50V2KX-1GP"
			(at 1.1811 -2.7051 270)
			(unlocked yes)
			(layer "F.Fab")
			(hide yes)
			(effects
				(font
					(size 1.016 1.016)
					(thickness 0.1524)
				)
			)
		)
		(property "Device Type" "C402H22"
			(at 1.1811 -4.2291 270)
			(unlocked yes)
			(layer "F.Fab")
			(hide yes)
			(effects
				(font
					(size 1.016 1.016)
					(thickness 0.1524)
				)
			)
		)
		(duplicate_pad_numbers_are_jumpers no)
		(fp_rect
			(start -0.4318 0.9525)
			(end 0.4318 -0.9525)
			(stroke
				(width 0)
				(type default)
			)
			(fill no)
			(layer "F.CrtYd")
		)
		(fp_rect
			(start -0.4318 0.9525)
			(end 0.4318 -0.9525)
			(stroke
				(width 0)
				(type default)
			)
			(fill no)
			(layer "F.Fab")
		)
		(pad "1" smd custom
			(at 0 -0.4445 270)
			(size 0.1524 0.1524)
			(layers "F.Cu" "F.Mask" "F.Paste")
			(net "SAS2X28_DRIVE_RX_P_A4")
			(options
				(clearance outline)
				(anchor circle)
			)
			(primitives
				(gr_poly
					(pts
						(arc
							(start 0.3048 -0.2032)
							(mid 0.275042 -0.275042)
							(end 0.2032 -0.3048)
						)
						(arc
							(start -0.2032 -0.3048)
							(mid -0.275042 -0.275042)
							(end -0.3048 -0.2032)
						)
						(arc
							(start -0.3048 0.2032)
							(mid -0.275042 0.275042)
							(end -0.2032 0.3048)
						)
						(arc
							(start 0.2032 0.3048)
							(mid 0.275042 0.275042)
							(end 0.3048 0.2032)
						)
					)
					(width 0)
					(fill yes)
				)
			)
		)
		(pad "2" smd custom
			(at 0 0.4445 270)
			(size 0.1524 0.1524)
			(layers "F.Cu" "F.Mask" "F.Paste")
			(net "SAS2X28_A_HDD4_RX_+")
			(options
				(clearance outline)
				(anchor circle)
			)
			(primitives
				(gr_poly
					(pts
						(arc
							(start 0.3048 -0.2032)
							(mid 0.275042 -0.275042)
							(end 0.2032 -0.3048)
						)
						(arc
							(start -0.2032 -0.3048)
							(mid -0.275042 -0.275042)
							(end -0.3048 -0.2032)
						)
						(arc
							(start -0.3048 0.2032)
							(mid -0.275042 0.275042)
							(end -0.2032 0.3048)
						)
						(arc
							(start 0.2032 0.3048)
							(mid 0.275042 0.275042)
							(end 0.3048 0.2032)
						)
					)
					(width 0)
					(fill yes)
				)
			)
		)
	)
	(footprint ""
		(layer "F.Cu")
		(at 217.854784 -161.006028 -90)
		(property "Reference" "C151"
			(at 0 0 270)
			(layer "F.SilkS")
			(hide yes)
			(effects
				(font
					(size 1.27 1.27)
				)
			)
		)
		(property "Value" "SCD01U50V2KX-1GP"
			(at 1.1811 -2.7051 270)
			(unlocked yes)
			(layer "F.Fab")
			(hide yes)
			(effects
				(font
					(size 1.016 1.016)
					(thickness 0.1524)
				)
			)
		)
		(property "Device Type" "C402H22"
			(at 1.1811 -4.2291 270)
			(unlocked yes)
			(layer "F.Fab")
			(hide yes)
			(effects
				(font
					(size 1.016 1.016)
					(thickness 0.1524)
				)
			)
		)
		(duplicate_pad_numbers_are_jumpers no)
		(fp_rect
			(start -0.4318 0.9525)
			(end 0.4318 -0.9525)
			(stroke
				(width 0)
				(type default)
			)
			(fill no)
			(layer "F.CrtYd")
		)
		(fp_rect
			(start -0.4318 0.9525)
			(end 0.4318 -0.9525)
			(stroke
				(width 0)
				(type default)
			)
			(fill no)
			(layer "F.Fab")
		)
		(pad "1" smd custom
			(at 0 -0.4445 270)
			(size 0.1524 0.1524)
			(layers "F.Cu" "F.Mask" "F.Paste")
			(net "SAS2X28_DRIVE_RX_P_A3")
			(options
				(clearance outline)
				(anchor circle)
			)
			(primitives
				(gr_poly
					(pts
						(arc
							(start 0.3048 -0.2032)
							(mid 0.275042 -0.275042)
							(end 0.2032 -0.3048)
						)
						(arc
							(start -0.2032 -0.3048)
							(mid -0.275042 -0.275042)
							(end -0.3048 -0.2032)
						)
						(arc
							(start -0.3048 0.2032)
							(mid -0.275042 0.275042)
							(end -0.2032 0.3048)
						)
						(arc
							(start 0.2032 0.3048)
							(mid 0.275042 0.275042)
							(end 0.3048 0.2032)
						)
					)
					(width 0)
					(fill yes)
				)
			)
		)
		(pad "2" smd custom
			(at 0 0.4445 270)
			(size 0.1524 0.1524)
			(layers "F.Cu" "F.Mask" "F.Paste")
			(net "SAS2X28_A_HDD3_RX_+")
			(options
				(clearance outline)
				(anchor circle)
			)
			(primitives
				(gr_poly
					(pts
						(arc
							(start 0.3048 -0.2032)
							(mid 0.275042 -0.275042)
							(end 0.2032 -0.3048)
						)
						(arc
							(start -0.2032 -0.3048)
							(mid -0.275042 -0.275042)
							(end -0.3048 -0.2032)
						)
						(arc
							(start -0.3048 0.2032)
							(mid -0.275042 0.275042)
							(end -0.2032 0.3048)
						)
						(arc
							(start 0.2032 0.3048)
							(mid 0.275042 0.275042)
							(end 0.3048 0.2032)
						)
					)
					(width 0)
					(fill yes)
				)
			)
		)
	)
	(footprint ""
		(layer "F.Cu")
		(at 78.612746 -194.8307 90)
		(property "Reference" "R221"
			(at 0 0 90)
			(layer "F.SilkS")
			(hide yes)
			(effects
				(font
					(size 1.27 1.27)
				)
			)
		)
		(property "Value" "4K7R2J-2-GP"
			(at 0.064008 -3.993896 90)
			(unlocked yes)
			(layer "F.Fab")
			(hide yes)
			(effects
				(font
					(size 1.016 1.016)
					(thickness 0.1524)
				)
			)
		)
		(property "Device Type" "R402H16"
			(at 0.064008 -5.517896 90)
			(unlocked yes)
			(layer "F.Fab")
			(hide yes)
			(effects
				(font
					(size 1.016 1.016)
					(thickness 0.1524)
				)
			)
		)
		(duplicate_pad_numbers_are_jumpers no)
		(fp_line
			(start 0.508 -0.9398)
			(end -0.508 -0.9398)
			(stroke
				(width 0.1524)
				(type default)
			)
			(layer "F.SilkS")
		)
		(fp_line
			(start -0.508 -0.9398)
			(end -0.508 0.9398)
			(stroke
				(width 0.1524)
				(type default)
			)
			(layer "F.SilkS")
		)
		(fp_rect
			(start -0.508 0.9398)
			(end 0.508 -0.9398)
			(stroke
				(width 0)
				(type default)
			)
			(fill no)
			(layer "F.CrtYd")
		)
		(fp_rect
			(start -0.508 0.9398)
			(end 0.508 -0.9398)
			(stroke
				(width 0)
				(type default)
			)
			(fill no)
			(layer "F.Fab")
		)
		(pad "1" smd custom
			(at 0 -0.4445 90)
			(size 0.1397 0.1397)
			(layers "F.Cu" "F.Mask" "F.Paste")
			(net "P12V")
			(options
				(clearance outline)
				(anchor circle)
			)
			(primitives
				(gr_poly
					(pts
						(arc
							(start -0.1778 -0.2794)
							(mid -0.249642 -0.249642)
							(end -0.2794 -0.1778)
						)
						(arc
							(start -0.2794 0.1778)
							(mid -0.249642 0.249642)
							(end -0.1778 0.2794)
						)
						(arc
							(start 0.1778 0.2794)
							(mid 0.249642 0.249642)
							(end 0.2794 0.1778)
						)
						(arc
							(start 0.2794 -0.1778)
							(mid 0.249642 -0.249642)
							(end 0.1778 -0.2794)
						)
					)
					(width 0)
					(fill yes)
				)
			)
		)
		(pad "2" smd custom
			(at 0 0.4445 90)
			(size 0.1397 0.1397)
			(layers "F.Cu" "F.Mask" "F.Paste")
			(net "SW_HDD8_R")
			(options
				(clearance outline)
				(anchor circle)
			)
			(primitives
				(gr_poly
					(pts
						(arc
							(start -0.1778 -0.2794)
							(mid -0.249642 -0.249642)
							(end -0.2794 -0.1778)
						)
						(arc
							(start -0.2794 0.1778)
							(mid -0.249642 0.249642)
							(end -0.1778 0.2794)
						)
						(arc
							(start 0.1778 0.2794)
							(mid 0.249642 0.249642)
							(end 0.2794 0.1778)
						)
						(arc
							(start 0.2794 -0.1778)
							(mid 0.249642 -0.249642)
							(end 0.1778 -0.2794)
						)
					)
					(width 0)
					(fill yes)
				)
			)
		)
	)
	(footprint ""
		(layer "F.Cu")
		(at 26.14803 -133.600952 90)
		(property "Reference" "C312"
			(at 0 0 90)
			(layer "F.SilkS")
			(hide yes)
			(effects
				(font
					(size 1.27 1.27)
				)
			)
		)
		(property "Value" "SCD01U50V2KX-1GP"
			(at 1.1811 -2.7051 90)
			(unlocked yes)
			(layer "F.Fab")
			(hide yes)
			(effects
				(font
					(size 1.016 1.016)
					(thickness 0.1524)
				)
			)
		)
		(property "Device Type" "C402H22"
			(at 1.1811 -4.2291 90)
			(unlocked yes)
			(layer "F.Fab")
			(hide yes)
			(effects
				(font
					(size 1.016 1.016)
					(thickness 0.1524)
				)
			)
		)
		(duplicate_pad_numbers_are_jumpers no)
		(fp_rect
			(start -0.4318 0.9525)
			(end 0.4318 -0.9525)
			(stroke
				(width 0)
				(type default)
			)
			(fill no)
			(layer "F.CrtYd")
		)
		(fp_rect
			(start -0.4318 0.9525)
			(end 0.4318 -0.9525)
			(stroke
				(width 0)
				(type default)
			)
			(fill no)
			(layer "F.Fab")
		)
		(pad "1" smd custom
			(at 0 -0.4445 90)
			(size 0.1524 0.1524)
			(layers "F.Cu" "F.Mask" "F.Paste")
			(net "SAS2X28_DRIVE_RX_N_B13")
			(options
				(clearance outline)
				(anchor circle)
			)
			(primitives
				(gr_poly
					(pts
						(arc
							(start 0.3048 -0.2032)
							(mid 0.275042 -0.275042)
							(end 0.2032 -0.3048)
						)
						(arc
							(start -0.2032 -0.3048)
							(mid -0.275042 -0.275042)
							(end -0.3048 -0.2032)
						)
						(arc
							(start -0.3048 0.2032)
							(mid -0.275042 0.275042)
							(end -0.2032 0.3048)
						)
						(arc
							(start 0.2032 0.3048)
							(mid 0.275042 0.275042)
							(end 0.3048 0.2032)
						)
					)
					(width 0)
					(fill yes)
				)
			)
		)
		(pad "2" smd custom
			(at 0 0.4445 90)
			(size 0.1524 0.1524)
			(layers "F.Cu" "F.Mask" "F.Paste")
			(net "SAS2X28_B_HDD13_RX_-")
			(options
				(clearance outline)
				(anchor circle)
			)
			(primitives
				(gr_poly
					(pts
						(arc
							(start 0.3048 -0.2032)
							(mid 0.275042 -0.275042)
							(end 0.2032 -0.3048)
						)
						(arc
							(start -0.2032 -0.3048)
							(mid -0.275042 -0.275042)
							(end -0.3048 -0.2032)
						)
						(arc
							(start -0.3048 0.2032)
							(mid -0.275042 0.275042)
							(end -0.2032 0.3048)
						)
						(arc
							(start 0.2032 0.3048)
							(mid 0.275042 0.275042)
							(end 0.3048 0.2032)
						)
					)
					(width 0)
					(fill yes)
				)
			)
		)
	)
)
